# TIMECARD (Time Appliance Project (Time Card)) — schematic netlist excerpt (pin names and nets, part order shuffled) for the footprints in the layout excerpt that follows; sources: Cadence DE-HDL packaged netlist, KiCad conversion of R4006-B0001-02_R01.brd

R345  RESISTOR  33OHM 1%  pkg SMC_0402R_H016  page 16 : \1\ = EEPROM_SDA ; \2\ = PRI_EEPROM_SDA
C4  CAPACITOR  0.22UF 6.3V 10%  pkg SMC_0201R  page 27 : \1\ = SG ; \2\ = XP12R0V_A_TIMER
TP38  TP_PIONT  pkg TP010CT020B030_PTH  page 25 : \1\ = XP3R3V_PG

(kicad_pcb
	(version 20260206)
	(generator "pcbnew")
	(generator_version "10.0")
	(general
		(thickness 1.6)
		(legacy_teardrops no)
	)
	(paper "A4")
	(title_block
		(title "timecard-production-celestica-r4006 — R4006-B0001-02_R01.brd")
		(comment 1 "Time Appliance Project (Time Card) / footprints 519-521 of 1113")
	)
	(layers
		(0 "F.Cu" signal "TOP")
		(4 "In1.Cu" signal "L02_GND1")
		(6 "In2.Cu" signal "L03_SIG1")
		(8 "In3.Cu" signal "L04_GND2")
		(10 "In4.Cu" signal "L05_VCC1")
		(12 "In5.Cu" signal "L06_VCC2")
		(14 "In6.Cu" signal "L07_GND3")
		(16 "In7.Cu" signal "L08_SIG2")
		(18 "In8.Cu" signal "L09_GND4")
		(2 "B.Cu" signal "BOTTOM")
		(9 "F.Adhes" user "F.Adhesive")
		(11 "B.Adhes" user "B.Adhesive")
		(13 "F.Paste" user "Package Geometry/Pastemask Top")
		(15 "B.Paste" user "Package Geometry/Pastemask Bottom")
		(5 "F.SilkS" user "Ref Des/Silkscreen Top")
		(7 "B.SilkS" user "Ref Des/Silkscreen Bottom")
		(1 "F.Mask" user "Board Geometry/Soldermask Top")
		(3 "B.Mask" user "Board Geometry/Soldermask Bottom")
		(17 "Dwgs.User" user "User.Drawings")
		(19 "Cmts.User" user "User.Comments")
		(21 "Eco1.User" user "User.Eco1")
		(23 "Eco2.User" user "User.Eco2")
		(25 "Edge.Cuts" user "Board Geometry/Outline")
		(27 "Margin" user)
		(31 "F.CrtYd" user "Package Geometry/Place Bound Top")
		(29 "B.CrtYd" user "Package Geometry/Place Bound Bottom")
		(35 "F.Fab" user "Ref Des/Assembly Top")
		(33 "B.Fab" user "Ref Des/Assembly Bottom")
	)
	(footprint ""
		(layer "F.Cu")
		(at 30.34538 -16.72844 180)
		(property "Reference" "R345"
			(at 0.889 5.16763 0)
			(unlocked yes)
			(layer "F.SilkS")
			(effects
				(font
					(size 0.7874 0.5842)
					(thickness 0.1524)
				)
			)
		)
		(property "Value" "VAL*"
			(at 0.02032 2.13233 180)
			(unlocked yes)
			(layer "F.Fab")
			(hide yes)
			(effects
				(font
					(size 0.7874 0.5842)
					(thickness 0.1524)
				)
			)
		)
		(property "Tolerance" "TOL*"
			(at 0.044704 3.05435 180)
			(unlocked yes)
			(layer "Cmts.User")
			(hide yes)
			(effects
				(font
					(size 0.7874 0.5842)
					(thickness 0.1524)
				)
			)
		)
		(property "User Part Number" "PARTNUM*"
			(at 0.02032 4.024884 180)
			(unlocked yes)
			(layer "Cmts.User")
			(hide yes)
			(effects
				(font
					(size 0.7874 0.5842)
					(thickness 0.1524)
				)
			)
		)
		(property "Device Type" "RESISTOR-G155-133R0-01,33OHM,1%"
			(at 0.008382 1.210564 180)
			(unlocked yes)
			(layer "F.Fab")
			(hide yes)
			(effects
				(font
					(size 0.7874 0.5842)
					(thickness 0.1524)
				)
			)
		)
		(duplicate_pad_numbers_are_jumpers no)
		(fp_line
			(start 1.143 0.5588)
			(end 1.143 -0.5588)
			(stroke
				(width 0.1)
				(type default)
			)
			(layer "F.SilkS")
		)
		(fp_line
			(start 1.143 -0.5588)
			(end -1.143 -0.5588)
			(stroke
				(width 0.1)
				(type default)
			)
			(layer "F.SilkS")
		)
		(fp_line
			(start -1.143 0.5588)
			(end 1.143 0.5588)
			(stroke
				(width 0.1)
				(type default)
			)
			(layer "F.SilkS")
		)
		(fp_line
			(start -1.143 -0.5588)
			(end -1.143 0.5588)
			(stroke
				(width 0.1)
				(type default)
			)
			(layer "F.SilkS")
		)
		(fp_rect
			(start 1.143 -0.5588)
			(end -1.143 0.5588)
			(stroke
				(width 0)
				(type default)
			)
			(fill no)
			(layer "F.CrtYd")
		)
		(fp_line
			(start 0.508 0.3048)
			(end 0.508 -0.3048)
			(stroke
				(width 0.1)
				(type default)
			)
			(layer "F.Fab")
		)
		(fp_line
			(start 0.508 -0.3048)
			(end -0.508 -0.3048)
			(stroke
				(width 0.1)
				(type default)
			)
			(layer "F.Fab")
		)
		(fp_line
			(start -0.508 0.3048)
			(end 0.508 0.3048)
			(stroke
				(width 0.1)
				(type default)
			)
			(layer "F.Fab")
		)
		(fp_line
			(start -0.508 -0.3048)
			(end -0.508 0.3048)
			(stroke
				(width 0.1)
				(type default)
			)
			(layer "F.Fab")
		)
		(pad "1" smd rect
			(at -0.5334 0 180)
			(size 0.7112 0.6096)
			(layers "F.Cu" "F.Mask" "F.Paste")
			(net "EEPROM_SDA")
		)
		(pad "2" smd rect
			(at 0.5334 0 180)
			(size 0.7112 0.6096)
			(layers "F.Cu" "F.Mask" "F.Paste")
			(net "PRI_EEPROM_SDA")
		)
		(zone
			(layer "F.Cu")
			(hatch none 0.5)
			(connect_pads
				(clearance 0)
			)
			(min_thickness 0.25)
			(keepout
				(tracks allowed)
				(vias not_allowed)
				(pads allowed)
				(copperpour not_allowed)
				(footprints allowed)
			)
			(placement
				(enabled no)
				(sheetname "")
			)
			(fill
				(thermal_gap 0.5)
				(thermal_bridge_width 0.5)
				(island_removal_mode 0)
			)
			(polygon
				(pts
					(xy 30.26918 -16.42364) (xy 30.42158 -16.42364) (xy 30.42158 -17.03324) (xy 30.26918 -17.03324)
				)
			)
		)
	)
	(footprint ""
		(layer "F.Cu")
		(at 95.123 -106.299)
		(property "Reference" "TP38"
			(at 0.8382 -0.08763 0)
			(unlocked yes)
			(layer "F.SilkS")
			(effects
				(font
					(size 0.7874 0.5842)
					(thickness 0.1524)
				)
				(justify left)
			)
		)
		(property "Value" ""
			(at 0 0 0)
			(layer "F.Fab")
			(effects
				(font
					(size 1.27 1.27)
				)
			)
		)
		(property "Device Type" "TP_PIONT-TP010CT020B030_PTH-TPA"
			(at -1.341882 0.996696 0)
			(unlocked yes)
			(layer "F.Fab")
			(hide yes)
			(effects
				(font
					(size 0.7874 0.5842)
					(thickness 0.000001)
				)
				(justify left)
			)
		)
		(duplicate_pad_numbers_are_jumpers no)
		(fp_poly
			(pts
				(arc
					(start 0.889 0)
					(mid -0.889 0)
					(end 0.889 0)
				)
			)
			(stroke
				(width 0)
				(type default)
			)
			(fill no)
			(layer "B.CrtYd")
		)
		(fp_poly
			(pts
				(arc
					(start 0.889 0)
					(mid -0.889 0)
					(end 0.889 0)
				)
			)
			(stroke
				(width 0)
				(type default)
			)
			(fill no)
			(layer "F.CrtYd")
		)
		(pad "1" thru_hole circle
			(at 0 0)
			(size 0.508 0.508)
			(drill 0.254)
			(layers "*.Cu" "*.Mask")
			(remove_unused_layers no)
			(net "XP3R3V_PG")
			(clearance 0.1016)
			(padstack
				(mode front_inner_back)
				(layer "Inner"
					(shape circle)
					(size 0.508 0.508)
					(clearance 0.1016)
				)
				(layer "B.Cu"
					(shape circle)
					(size 0.762 0.762)
					(clearance -0.0254)
				)
			)
		)
	)
	(footprint ""
		(layer "F.Cu")
		(at 145.3134 -94.2848 180)
		(property "Reference" "C4"
			(at -0.2286 -8.85317 0)
			(unlocked yes)
			(layer "F.SilkS")
			(effects
				(font
					(size 0.7874 0.5842)
					(thickness 0.1524)
				)
			)
		)
		(property "Value" "VAL*"
			(at 0.193548 2.13614 180)
			(unlocked yes)
			(layer "F.Fab")
			(hide yes)
			(effects
				(font
					(size 0.7874 0.5842)
					(thickness 0.1524)
				)
			)
		)
		(property "Tolerance" "TOL*"
			(at 0.216154 3.1496 180)
			(unlocked yes)
			(layer "Cmts.User")
			(hide yes)
			(effects
				(font
					(size 0.7874 0.5842)
					(thickness 0.1524)
				)
			)
		)
		(property "Device Type" "CAPACITOR-G104-0F224-BK,0.22UFA"
			(at 0.184404 1.180592 180)
			(unlocked yes)
			(layer "F.Fab")
			(hide yes)
			(effects
				(font
					(size 0.7874 0.5842)
					(thickness 0.1524)
				)
			)
		)
		(property "User Part Number" "PARTNUM*"
			(at 0.216154 4.185666 180)
			(unlocked yes)
			(layer "Cmts.User")
			(hide yes)
			(effects
				(font
					(size 0.7874 0.5842)
					(thickness 0.1524)
				)
			)
		)
		(duplicate_pad_numbers_are_jumpers no)
		(fp_line
			(start 0.671322 0.4445)
			(end -0.671322 0.4445)
			(stroke
				(width 0.1)
				(type default)
			)
			(layer "F.SilkS")
		)
		(fp_line
			(start 0.671322 -0.4445)
			(end 0.671322 0.4445)
			(stroke
				(width 0.1)
				(type default)
			)
			(layer "F.SilkS")
		)
		(fp_line
			(start -0.671322 0.4445)
			(end -0.671322 -0.4445)
			(stroke
				(width 0.1)
				(type default)
			)
			(layer "F.SilkS")
		)
		(fp_line
			(start -0.671322 -0.4445)
			(end 0.671322 -0.4445)
			(stroke
				(width 0.1)
				(type default)
			)
			(layer "F.SilkS")
		)
		(fp_rect
			(start 0.671322 -0.4445)
			(end -0.671322 0.4445)
			(stroke
				(width 0)
				(type default)
			)
			(fill no)
			(layer "F.CrtYd")
		)
		(fp_line
			(start 0.31496 0.1651)
			(end 0.31496 -0.1651)
			(stroke
				(width 0.1)
				(type default)
			)
			(layer "F.Fab")
		)
		(fp_line
			(start 0.31496 -0.1651)
			(end -0.31496 -0.1651)
			(stroke
				(width 0.1)
				(type default)
			)
			(layer "F.Fab")
		)
		(fp_line
			(start -0.31496 0.1651)
			(end 0.31496 0.1651)
			(stroke
				(width 0.1)
				(type default)
			)
			(layer "F.Fab")
		)
		(fp_line
			(start -0.31496 -0.1651)
			(end -0.31496 0.1651)
			(stroke
				(width 0.1)
				(type default)
			)
			(layer "F.Fab")
		)
		(pad "1" smd rect
			(at -0.264922 0 180)
			(size 0.3048 0.381)
			(layers "F.Cu" "F.Mask" "F.Paste")
			(net "SG")
		)
		(pad "2" smd rect
			(at 0.264922 0 180)
			(size 0.3048 0.381)
			(layers "F.Cu" "F.Mask" "F.Paste")
			(net "XP12R0V_A_TIMER")
		)
		(zone
			(layer "F.Cu")
			(hatch none 0.5)
			(connect_pads
				(clearance 0)
			)
			(min_thickness 0.25)
			(keepout
				(tracks allowed)
				(vias not_allowed)
				(pads allowed)
				(copperpour not_allowed)
				(footprints allowed)
			)
			(placement
				(enabled no)
				(sheetname "")
			)
			(fill
				(thermal_gap 0.5)
				(thermal_bridge_width 0.5)
				(island_removal_mode 0)
			)
			(polygon
				(pts
					(xy 145.200878 -94.0943) (xy 145.425922 -94.0943) (xy 145.425922 -94.4753) (xy 145.200878 -94.4753)
				)
			)
		)
	)
)
